# TIMECARD (Time Appliance Project (Time Card)) — schematic netlist excerpt (pin names and nets, part order shuffled) for the footprints in the layout excerpt that follows; sources: Cadence DE-HDL packaged netlist, KiCad conversion of R4006-B0001-02_R01.brd

R444  RESISTOR  10KOHM 1%  pkg SMC_0402R_H016  page 24 : \1\ = XP3R3V_FT4232 ; \2\ = FTDI_EE_DO
R177  RESISTOR  1.13KOHM 1%  pkg SMC_0402R  page 30 : \1\ = XP1R2V_VIN ; \2\ = XP1R2V_EN_R

(kicad_pcb
	(version 20260206)
	(generator "pcbnew")
	(generator_version "10.0")
	(general
		(thickness 1.6)
		(legacy_teardrops no)
	)
	(paper "A4")
	(title_block
		(title "timecard-production-celestica-r4006 — R4006-B0001-02_R01.brd")
		(comment 1 "Time Appliance Project (Time Card) / footprints 974-975 of 1113")
	)
	(layers
		(0 "F.Cu" signal "TOP")
		(4 "In1.Cu" signal "L02_GND1")
		(6 "In2.Cu" signal "L03_SIG1")
		(8 "In3.Cu" signal "L04_GND2")
		(10 "In4.Cu" signal "L05_VCC1")
		(12 "In5.Cu" signal "L06_VCC2")
		(14 "In6.Cu" signal "L07_GND3")
		(16 "In7.Cu" signal "L08_SIG2")
		(18 "In8.Cu" signal "L09_GND4")
		(2 "B.Cu" signal "BOTTOM")
		(9 "F.Adhes" user "F.Adhesive")
		(11 "B.Adhes" user "B.Adhesive")
		(13 "F.Paste" user "Package Geometry/Pastemask Top")
		(15 "B.Paste" user "Package Geometry/Pastemask Bottom")
		(5 "F.SilkS" user "Ref Des/Silkscreen Top")
		(7 "B.SilkS" user "Ref Des/Silkscreen Bottom")
		(1 "F.Mask" user "Board Geometry/Soldermask Top")
		(3 "B.Mask" user "Board Geometry/Soldermask Bottom")
		(17 "Dwgs.User" user "User.Drawings")
		(19 "Cmts.User" user "User.Comments")
		(21 "Eco1.User" user "User.Eco1")
		(23 "Eco2.User" user "User.Eco2")
		(25 "Edge.Cuts" user "Board Geometry/Outline")
		(27 "Margin" user)
		(31 "F.CrtYd" user "Package Geometry/Place Bound Top")
		(29 "B.CrtYd" user "Package Geometry/Place Bound Bottom")
		(35 "F.Fab" user "Ref Des/Assembly Top")
		(33 "B.Fab" user "Ref Des/Assembly Bottom")
	)
	(footprint ""
		(layer "B.Cu")
		(at 53.975 -85.344)
		(property "Reference" "R444"
			(at 0.127 -5.92963 0)
			(unlocked yes)
			(layer "B.SilkS")
			(effects
				(font
					(size 0.7874 0.5842)
					(thickness 0.1524)
				)
				(justify mirror)
			)
		)
		(property "Value" "VAL*"
			(at -0.02032 2.13233 0)
			(unlocked yes)
			(layer "B.Fab")
			(hide yes)
			(effects
				(font
					(size 0.7874 0.5842)
					(thickness 0.1524)
				)
				(justify mirror)
			)
		)
		(property "Tolerance" "TOL*"
			(at -0.044704 3.05435 0)
			(unlocked yes)
			(layer "Cmts.User")
			(hide yes)
			(effects
				(font
					(size 0.7874 0.5842)
					(thickness 0.1524)
				)
				(justify mirror)
			)
		)
		(property "User Part Number" "PARTNUM*"
			(at -0.02032 4.024884 0)
			(unlocked yes)
			(layer "Cmts.User")
			(hide yes)
			(effects
				(font
					(size 0.7874 0.5842)
					(thickness 0.1524)
				)
				(justify mirror)
			)
		)
		(property "Device Type" "RESISTOR-G155-11002-01,10KOHM,A"
			(at -0.008382 1.210564 0)
			(unlocked yes)
			(layer "B.Fab")
			(hide yes)
			(effects
				(font
					(size 0.7874 0.5842)
					(thickness 0.1524)
				)
				(justify mirror)
			)
		)
		(duplicate_pad_numbers_are_jumpers no)
		(fp_line
			(start -1.143 -0.5588)
			(end 1.143 -0.5588)
			(stroke
				(width 0.1)
				(type default)
			)
			(layer "B.SilkS")
		)
		(fp_line
			(start -1.143 0.5588)
			(end -1.143 -0.5588)
			(stroke
				(width 0.1)
				(type default)
			)
			(layer "B.SilkS")
		)
		(fp_line
			(start 1.143 -0.5588)
			(end 1.143 0.5588)
			(stroke
				(width 0.1)
				(type default)
			)
			(layer "B.SilkS")
		)
		(fp_line
			(start 1.143 0.5588)
			(end -1.143 0.5588)
			(stroke
				(width 0.1)
				(type default)
			)
			(layer "B.SilkS")
		)
		(fp_poly
			(pts
				(xy 1.143 0.5588) (xy -1.143 0.5588) (xy -1.143 -0.5588) (xy 1.143 -0.5588)
			)
			(stroke
				(width 0)
				(type default)
			)
			(fill no)
			(layer "B.CrtYd")
		)
		(fp_line
			(start -0.508 -0.3048)
			(end 0.508 -0.3048)
			(stroke
				(width 0.1)
				(type default)
			)
			(layer "B.Fab")
		)
		(fp_line
			(start -0.508 0.3048)
			(end -0.508 -0.3048)
			(stroke
				(width 0.1)
				(type default)
			)
			(layer "B.Fab")
		)
		(fp_line
			(start 0.508 -0.3048)
			(end 0.508 0.3048)
			(stroke
				(width 0.1)
				(type default)
			)
			(layer "B.Fab")
		)
		(fp_line
			(start 0.508 0.3048)
			(end -0.508 0.3048)
			(stroke
				(width 0.1)
				(type default)
			)
			(layer "B.Fab")
		)
		(pad "1" smd rect
			(at 0.5334 0 180)
			(size 0.7112 0.6096)
			(layers "B.Cu" "B.Mask" "B.Paste")
			(net "XP3R3V_FT4232")
		)
		(pad "2" smd rect
			(at -0.5334 0 180)
			(size 0.7112 0.6096)
			(layers "B.Cu" "B.Mask" "B.Paste")
			(net "FTDI_EE_DO")
		)
		(zone
			(layer "B.Cu")
			(hatch none 0.5)
			(connect_pads
				(clearance 0)
			)
			(min_thickness 0.25)
			(keepout
				(tracks allowed)
				(vias not_allowed)
				(pads allowed)
				(copperpour not_allowed)
				(footprints allowed)
			)
			(placement
				(enabled no)
				(sheetname "")
			)
			(fill
				(thermal_gap 0.5)
				(thermal_bridge_width 0.5)
				(island_removal_mode 0)
			)
			(polygon
				(pts
					(xy 54.0512 -85.0392) (xy 54.0512 -85.6488) (xy 53.8988 -85.6488) (xy 53.8988 -85.0392)
				)
			)
		)
		(zone
			(layer "B.Cu")
			(hatch none 0.5)
			(connect_pads
				(clearance 0)
			)
			(min_thickness 0.25)
			(keepout
				(tracks not_allowed)
				(vias allowed)
				(pads allowed)
				(copperpour not_allowed)
				(footprints allowed)
			)
			(placement
				(enabled no)
				(sheetname "")
			)
			(fill
				(thermal_gap 0.5)
				(thermal_bridge_width 0.5)
				(island_removal_mode 0)
			)
			(polygon
				(pts
					(xy 54.0512 -85.0392) (xy 54.0512 -85.6488) (xy 53.8988 -85.6488) (xy 53.8988 -85.0392)
				)
			)
		)
	)
	(footprint ""
		(layer "B.Cu")
		(at 96.8756 -78.5368 180)
		(property "Reference" "R177"
			(at 0.3556 1.30683 0)
			(unlocked yes)
			(layer "B.SilkS")
			(effects
				(font
					(size 0.7874 0.5842)
					(thickness 0.1524)
				)
				(justify mirror)
			)
		)
		(property "Value" "VAL*"
			(at -0.0508 2.245106 180)
			(unlocked yes)
			(layer "B.Fab")
			(hide yes)
			(effects
				(font
					(size 0.7874 0.5842)
					(thickness 0.1524)
				)
				(justify mirror)
			)
		)
		(property "Tolerance" "TOL*"
			(at -0.0508 3.261106 180)
			(unlocked yes)
			(layer "Cmts.User")
			(hide yes)
			(effects
				(font
					(size 0.7874 0.5842)
					(thickness 0.1524)
				)
				(justify mirror)
			)
		)
		(property "Device Type" "RESISTOR-G152-00055-01,1.13KOHA"
			(at -0.0762 1.254506 180)
			(unlocked yes)
			(layer "B.Fab")
			(hide yes)
			(effects
				(font
					(size 0.7874 0.5842)
					(thickness 0.1524)
				)
				(justify mirror)
			)
		)
		(property "User Part Number" "PARTNUM*"
			(at -0.0762 4.302506 180)
			(unlocked yes)
			(layer "Cmts.User")
			(hide yes)
			(effects
				(font
					(size 0.7874 0.5842)
					(thickness 0.1524)
				)
				(justify mirror)
			)
		)
		(duplicate_pad_numbers_are_jumpers no)
		(fp_line
			(start 1.143 0.5588)
			(end -1.143 0.5588)
			(stroke
				(width 0.1)
				(type default)
			)
			(layer "B.SilkS")
		)
		(fp_line
			(start 1.143 -0.5588)
			(end 1.143 0.5588)
			(stroke
				(width 0.1)
				(type default)
			)
			(layer "B.SilkS")
		)
		(fp_line
			(start -1.143 0.5588)
			(end -1.143 -0.5588)
			(stroke
				(width 0.1)
				(type default)
			)
			(layer "B.SilkS")
		)
		(fp_line
			(start -1.143 -0.5588)
			(end 1.143 -0.5588)
			(stroke
				(width 0.1)
				(type default)
			)
			(layer "B.SilkS")
		)
		(fp_rect
			(start 1.143 0.5588)
			(end -1.143 -0.5588)
			(stroke
				(width 0)
				(type default)
			)
			(fill no)
			(layer "B.CrtYd")
		)
		(fp_line
			(start 0.508 0.3048)
			(end -0.508 0.3048)
			(stroke
				(width 0.1)
				(type default)
			)
			(layer "B.Fab")
		)
		(fp_line
			(start 0.508 -0.3048)
			(end 0.508 0.3048)
			(stroke
				(width 0.1)
				(type default)
			)
			(layer "B.Fab")
		)
		(fp_line
			(start -0.508 0.3048)
			(end -0.508 -0.3048)
			(stroke
				(width 0.1)
				(type default)
			)
			(layer "B.Fab")
		)
		(fp_line
			(start -0.508 -0.3048)
			(end 0.508 -0.3048)
			(stroke
				(width 0.1)
				(type default)
			)
			(layer "B.Fab")
		)
		(pad "1" smd rect
			(at 0.5334 0)
			(size 0.7112 0.6096)
			(layers "B.Cu" "B.Mask" "B.Paste")
			(net "XP1R2V_VIN")
		)
		(pad "2" smd rect
			(at -0.5334 0)
			(size 0.7112 0.6096)
			(layers "B.Cu" "B.Mask" "B.Paste")
			(net "XP1R2V_EN_R")
		)
		(zone
			(layer "B.Cu")
			(hatch none 0.5)
			(connect_pads
				(clearance 0)
			)
			(min_thickness 0.25)
			(keepout
				(tracks allowed)
				(vias not_allowed)
				(pads allowed)
				(copperpour not_allowed)
				(footprints allowed)
			)
			(placement
				(enabled no)
				(sheetname "")
			)
			(fill
				(thermal_gap 0.5)
				(thermal_bridge_width 0.5)
				(island_removal_mode 0)
			)
			(polygon
				(pts
					(xy 96.7994 -78.8416) (xy 96.7994 -78.232) (xy 96.9518 -78.232) (xy 96.9518 -78.8416)
				)
			)
		)
	)
)
